FILE_TYPE = MULTI_PHYS_TABLE;

PART 'CONN8_TSW10407FD'

{========================================================================================}
:VALUE                  | PART_TYPE | MATERIAL | PART_NUMBER      = STANDARD        | LIFECYCLE      | PART_NUMBER   | JEDEC_TYPE      | DESCRIPTION                                     | MANUFTR | MANUF_PN         | RD_CMPLS_LVL | CMPLS_LVL | CLASS | DIP_SMD | FROM_PJ        | DATA                           | FP_ECN               | EE_CHECK_LIST | CREATOR | CREATEDAY  | PSL | STATUS | ESD_CDM | ESD_HBM | ESD_MM | MSD | PIN_LENGTH_LONG_PIN | PIN_LENGTH_SHORT_PIN ;
{========================================================================================}
 'CONN8_TSW-104-07-F-D' | 'THLF'    | 'IO'     | 'DFHD08MS225'(!) = ''               | ''               | 'DFHD08MS225' |'HEADER2X4XF'| 'CONN DIP HEADER 8P 2R MS(P2.54,H8.38)'         | 'STC'   | 'TSW-104-07-F-D' | 'EU(V1)'     | 'EU(V1)'  | 'IO'  | 'DIP'   | 'T2MK-CHIA-LU' | 'STC_TSW-104-07-F-D_REVDN.pdf' | 'TSW-104-07-F-D.msg' | ''            | ''      | '20210514' | ''  | ''     | ''      | ''      | ''     | ''  | '100 MILS'          | '100 MILS'          
 'CONN8_TSW-104-07-F-D' | 'THLF'    | 'EMPTY'  | 'DFHD08MS225'(!) = ''               | ''               | 'DFHD08MS225' |'HEADER2X4XF'| 'CONN DIP HEADER 8P 2R MS(P2.54,H8.38)'         | 'STC'   | 'TSW-104-07-F-D' | 'EU(V1)'     | 'EU(V1)'  | 'IO'  | 'DIP'   | 'T2MK-CHIA-LU' | 'STC_TSW-104-07-F-D_REVDN.pdf' | 'TSW-104-07-F-D.msg' | ''            | ''      | '20210514' | ''  | ''     | ''      | ''      | ''     | ''  | '100 MILS'          | '100 MILS'          
 'CONN8_TSW-104-07-F-D' | 'THLF'    | 'IO'     | 'SP_DFHD08MS225'(!) = ''               | ''               | 'DFHD08MS225' |'G_HEADER2X4XF'| 'CONN DIP HEADER 8P 2R MS(P2.54,H8.38)_FOR SEL' | 'STC'   | 'TSW-104-07-F-D' | 'EU(V1)'     | 'EU(V1)'  | 'IO'  | 'DIP'   | 'T2MK-CHIA-LU' | 'STC_TSW-104-07-F-D_REVDN.pdf' | 'TSW-104-07-F-D.msg' | ''            | ''      | '20210514' | ''  | ''     | ''      | ''      | ''     | ''  | '100 MILS'          | '100 MILS'          
 'CONN8_TSW-104-07-F-D' | 'THLF'    | 'EMPTY'  | 'SP_DFHD08MS225'(!) = ''               | ''               | 'DFHD08MS225' |'G_HEADER2X4XF'| 'CONN DIP HEADER 8P 2R MS(P2.54,H8.38)_FOR SEL' | 'STC'   | 'TSW-104-07-F-D' | 'EU(V1)'     | 'EU(V1)'  | 'IO'  | 'DIP'   | 'T2MK-CHIA-LU' | 'STC_TSW-104-07-F-D_REVDN.pdf' | 'TSW-104-07-F-D.msg' | ''            | ''      | '20210514' | ''  | ''     | ''      | ''      | ''     | ''  | '100 MILS'          | '100 MILS'          

END_PART

END.

